(kicad_pcb
	(version 20260206)
	(generator "pcbnew")
	(generator_version "10.0")
	(general
		(thickness 1.6)
		(legacy_teardrops no)
	)
	(paper "A4")
	(title_block
		(title "03242023_DA0F0TMBIJ0_F0T_Motherboard_J_brd_V01_OCP.brd")
		(comment 1 "Grand Teton / footprints 5729-5735 of 6105")
	)
	(layers
		(0 "F.Cu" signal "TOP")
		(4 "In1.Cu" signal "GND")
		(6 "In2.Cu" signal "IN1")
		(8 "In3.Cu" signal "GND1")
		(10 "In4.Cu" signal "IN2")
		(12 "In5.Cu" signal "GND2")
		(14 "In6.Cu" signal "IN3")
		(16 "In7.Cu" signal "GND3")
		(18 "In8.Cu" signal "VCC")
		(20 "In9.Cu" signal "VCC1")
		(22 "In10.Cu" signal "GND4")
		(24 "In11.Cu" signal "IN4")
		(26 "In12.Cu" signal "GND5")
		(28 "In13.Cu" signal "IN5")
		(30 "In14.Cu" signal "GND6")
		(32 "In15.Cu" signal "IN6")
		(34 "In16.Cu" signal "GND7")
		(2 "B.Cu" signal "BOTTOM")
		(9 "F.Adhes" user "F.Adhesive")
		(11 "B.Adhes" user "B.Adhesive")
		(13 "F.Paste" user "Package Geometry/Pastemask Top")
		(15 "B.Paste" user "Package Geometry/Pastemask Bottom")
		(5 "F.SilkS" user "Ref Des/Silkscreen Top")
		(7 "B.SilkS" user "Ref Des/Silkscreen Bottom")
		(1 "F.Mask" user "Board Geometry/Soldermask Top")
		(3 "B.Mask" user "Board Geometry/Soldermask Bottom")
		(17 "Dwgs.User" user "User.Drawings")
		(19 "Cmts.User" user "User.Comments")
		(21 "Eco1.User" user "User.Eco1")
		(23 "Eco2.User" user "User.Eco2")
		(25 "Edge.Cuts" user "Board Geometry/Outline")
		(27 "Margin" user)
		(31 "F.CrtYd" user "Package Geometry/Place Bound Top")
		(29 "B.CrtYd" user "Package Geometry/Place Bound Bottom")
		(35 "F.Fab" user "Ref Des/Assembly Top")
		(33 "B.Fab" user "Ref Des/Assembly Bottom")
	)
	(footprint ""
		(layer "B.Cu")
		(at 201.08799 -318.997076 90)
		(property "Reference" "R905"
			(at 0 0 90)
			(layer "B.SilkS")
			(hide yes)
			(effects
				(font
					(size 1.27 1.27)
				)
				(justify mirror)
			)
		)
		(property "Value" ""
			(at 0 0 90)
			(layer "B.Fab")
			(effects
				(font
					(size 1.27 1.27)
				)
				(justify mirror)
			)
		)
		(duplicate_pad_numbers_are_jumpers no)
		(fp_line
			(start 0.7874 -0.4064)
			(end -0.7874 -0.4064)
			(stroke
				(width 0.1524)
				(type default)
			)
			(layer "B.SilkS")
		)
		(fp_line
			(start -0.7874 -0.4064)
			(end -0.7874 0.4064)
			(stroke
				(width 0.1524)
				(type default)
			)
			(layer "B.SilkS")
		)
		(fp_line
			(start 0.7874 0.4064)
			(end 0.7874 -0.4064)
			(stroke
				(width 0.1524)
				(type default)
			)
			(layer "B.SilkS")
		)
		(fp_line
			(start -0.7874 0.4064)
			(end 0.7874 0.4064)
			(stroke
				(width 0.1524)
				(type default)
			)
			(layer "B.SilkS")
		)
		(fp_line
			(start 0.67945 -0.305054)
			(end 0.12065 -0.305054)
			(stroke
				(width 0.1)
				(type default)
			)
			(layer "B.Fab")
		)
		(fp_line
			(start 0.12065 -0.305054)
			(end 0.12065 -0.2794)
			(stroke
				(width 0.1)
				(type default)
			)
			(layer "B.Fab")
		)
		(fp_line
			(start -0.12065 -0.3048)
			(end -0.67945 -0.3048)
			(stroke
				(width 0.1)
				(type default)
			)
			(layer "B.Fab")
		)
		(fp_line
			(start -0.67945 -0.3048)
			(end -0.67945 0.3048)
			(stroke
				(width 0.1)
				(type default)
			)
			(layer "B.Fab")
		)
		(fp_line
			(start 0.12065 -0.2794)
			(end -0.12065 -0.2794)
			(stroke
				(width 0.1)
				(type default)
			)
			(layer "B.Fab")
		)
		(fp_line
			(start -0.12065 -0.2794)
			(end -0.12065 -0.3048)
			(stroke
				(width 0.1)
				(type default)
			)
			(layer "B.Fab")
		)
		(fp_line
			(start 0.12065 0.2794)
			(end 0.12065 0.3048)
			(stroke
				(width 0.1)
				(type default)
			)
			(layer "B.Fab")
		)
		(fp_line
			(start -0.120396 0.2794)
			(end 0.12065 0.2794)
			(stroke
				(width 0.1)
				(type default)
			)
			(layer "B.Fab")
		)
		(fp_line
			(start 0.67945 0.3048)
			(end 0.67945 -0.305054)
			(stroke
				(width 0.1)
				(type default)
			)
			(layer "B.Fab")
		)
		(fp_line
			(start 0.12065 0.3048)
			(end 0.67945 0.3048)
			(stroke
				(width 0.1)
				(type default)
			)
			(layer "B.Fab")
		)
		(fp_line
			(start -0.120396 0.3048)
			(end -0.120396 0.2794)
			(stroke
				(width 0.1)
				(type default)
			)
			(layer "B.Fab")
		)
		(fp_line
			(start -0.67945 0.3048)
			(end -0.120396 0.3048)
			(stroke
				(width 0.1)
				(type default)
			)
			(layer "B.Fab")
		)
		(pad "1" smd circle
			(at 0.40005 0 270)
			(size 0 0)
			(layers "B.Cu" "B.Mask" "B.Paste")
			(net "PWRGD_CHG_CPU1_DIMM1")
		)
		(pad "2" smd circle
			(at -0.40005 0 270)
			(size 0 0)
			(layers "B.Cu" "B.Mask" "B.Paste")
			(net "PWRGD_FAIL_CPU1_GH")
		)
	)
	(footprint ""
		(layer "B.Cu")
		(at 173.145958 -353.599242 90)
		(property "Reference" "PC403_P1_1"
			(at 0 0 90)
			(layer "B.SilkS")
			(hide yes)
			(effects
				(font
					(size 1.27 1.27)
				)
				(justify mirror)
			)
		)
		(property "Value" ""
			(at 0 0 90)
			(layer "B.Fab")
			(effects
				(font
					(size 1.27 1.27)
				)
				(justify mirror)
			)
		)
		(duplicate_pad_numbers_are_jumpers no)
		(fp_line
			(start 1.524 -0.762)
			(end -1.524 -0.762)
			(stroke
				(width 0.1524)
				(type default)
			)
			(layer "B.SilkS")
		)
		(fp_line
			(start -1.524 -0.762)
			(end -1.524 0.762)
			(stroke
				(width 0.1524)
				(type default)
			)
			(layer "B.SilkS")
		)
		(fp_line
			(start 1.524 0.762)
			(end 1.524 -0.762)
			(stroke
				(width 0.1524)
				(type default)
			)
			(layer "B.SilkS")
		)
		(fp_line
			(start -1.524 0.762)
			(end 1.524 0.762)
			(stroke
				(width 0.1524)
				(type default)
			)
			(layer "B.SilkS")
		)
		(fp_line
			(start 1.1049 -0.724916)
			(end 1.1049 0.724916)
			(stroke
				(width 0.1)
				(type default)
			)
			(layer "B.Fab")
		)
		(fp_line
			(start -1.1049 -0.724916)
			(end 1.1049 -0.724916)
			(stroke
				(width 0.1)
				(type default)
			)
			(layer "B.Fab")
		)
		(fp_line
			(start 1.1049 0.724916)
			(end -1.1049 0.724916)
			(stroke
				(width 0.1)
				(type default)
			)
			(layer "B.Fab")
		)
		(fp_line
			(start -1.1049 0.724916)
			(end -1.1049 -0.724916)
			(stroke
				(width 0.1)
				(type default)
			)
			(layer "B.Fab")
		)
		(pad "1" smd rect
			(at 0.889 0 90)
			(size 1.016 1.27)
			(layers "B.Cu" "B.Mask" "B.Paste")
			(net "SW_P12V_PVCCFA_EHV_FIVRA_CPU1_R")
		)
		(pad "2" smd rect
			(at -0.889 0 90)
			(size 1.016 1.27)
			(layers "B.Cu" "B.Mask" "B.Paste")
			(net "GND")
		)
	)
	(footprint ""
		(layer "B.Cu")
		(at 126.87554 -20.985988 -90)
		(property "Reference" "R4291"
			(at 0 0 90)
			(layer "B.SilkS")
			(hide yes)
			(effects
				(font
					(size 1.27 1.27)
				)
				(justify mirror)
			)
		)
		(property "Value" ""
			(at 0 0 90)
			(layer "B.Fab")
			(effects
				(font
					(size 1.27 1.27)
				)
				(justify mirror)
			)
		)
		(duplicate_pad_numbers_are_jumpers no)
		(fp_line
			(start -0.7874 0.4064)
			(end 0.7874 0.4064)
			(stroke
				(width 0.1524)
				(type default)
			)
			(layer "B.SilkS")
		)
		(fp_line
			(start 0.7874 0.4064)
			(end 0.7874 -0.4064)
			(stroke
				(width 0.1524)
				(type default)
			)
			(layer "B.SilkS")
		)
		(fp_line
			(start -0.7874 -0.4064)
			(end -0.7874 0.4064)
			(stroke
				(width 0.1524)
				(type default)
			)
			(layer "B.SilkS")
		)
		(fp_line
			(start 0.7874 -0.4064)
			(end -0.7874 -0.4064)
			(stroke
				(width 0.1524)
				(type default)
			)
			(layer "B.SilkS")
		)
		(fp_line
			(start -0.67945 0.3048)
			(end -0.120396 0.3048)
			(stroke
				(width 0.1)
				(type default)
			)
			(layer "B.Fab")
		)
		(fp_line
			(start -0.120396 0.3048)
			(end -0.120396 0.2794)
			(stroke
				(width 0.1)
				(type default)
			)
			(layer "B.Fab")
		)
		(fp_line
			(start 0.12065 0.3048)
			(end 0.67945 0.3048)
			(stroke
				(width 0.1)
				(type default)
			)
			(layer "B.Fab")
		)
		(fp_line
			(start 0.67945 0.3048)
			(end 0.67945 -0.305054)
			(stroke
				(width 0.1)
				(type default)
			)
			(layer "B.Fab")
		)
		(fp_line
			(start -0.120396 0.2794)
			(end 0.12065 0.2794)
			(stroke
				(width 0.1)
				(type default)
			)
			(layer "B.Fab")
		)
		(fp_line
			(start 0.12065 0.2794)
			(end 0.12065 0.3048)
			(stroke
				(width 0.1)
				(type default)
			)
			(layer "B.Fab")
		)
		(fp_line
			(start -0.12065 -0.2794)
			(end -0.12065 -0.3048)
			(stroke
				(width 0.1)
				(type default)
			)
			(layer "B.Fab")
		)
		(fp_line
			(start 0.12065 -0.2794)
			(end -0.12065 -0.2794)
			(stroke
				(width 0.1)
				(type default)
			)
			(layer "B.Fab")
		)
		(fp_line
			(start -0.67945 -0.3048)
			(end -0.67945 0.3048)
			(stroke
				(width 0.1)
				(type default)
			)
			(layer "B.Fab")
		)
		(fp_line
			(start -0.12065 -0.3048)
			(end -0.67945 -0.3048)
			(stroke
				(width 0.1)
				(type default)
			)
			(layer "B.Fab")
		)
		(fp_line
			(start 0.12065 -0.305054)
			(end 0.12065 -0.2794)
			(stroke
				(width 0.1)
				(type default)
			)
			(layer "B.Fab")
		)
		(fp_line
			(start 0.67945 -0.305054)
			(end 0.12065 -0.305054)
			(stroke
				(width 0.1)
				(type default)
			)
			(layer "B.Fab")
		)
		(pad "1" smd circle
			(at 0.40005 0 90)
			(size 0 0)
			(layers "B.Cu" "B.Mask" "B.Paste")
			(net "P3V3_AUX")
		)
		(pad "2" smd circle
			(at -0.40005 0 90)
			(size 0 0)
			(layers "B.Cu" "B.Mask" "B.Paste")
			(net "FM_USB3_1_EN_N")
		)
	)
	(footprint ""
		(layer "B.Cu")
		(at 127.907542 -366.723168 90)
		(property "Reference" "PC1269"
			(at 0 0 90)
			(layer "B.SilkS")
			(hide yes)
			(effects
				(font
					(size 1.27 1.27)
				)
				(justify mirror)
			)
		)
		(property "Value" ""
			(at 0 0 90)
			(layer "B.Fab")
			(effects
				(font
					(size 1.27 1.27)
				)
				(justify mirror)
			)
		)
		(duplicate_pad_numbers_are_jumpers no)
		(fp_line
			(start 1.524 -0.762)
			(end -1.524 -0.762)
			(stroke
				(width 0.1524)
				(type default)
			)
			(layer "B.SilkS")
		)
		(fp_line
			(start -1.524 -0.762)
			(end -1.524 0.762)
			(stroke
				(width 0.1524)
				(type default)
			)
			(layer "B.SilkS")
		)
		(fp_line
			(start 1.524 0.762)
			(end 1.524 -0.762)
			(stroke
				(width 0.1524)
				(type default)
			)
			(layer "B.SilkS")
		)
		(fp_line
			(start -1.524 0.762)
			(end 1.524 0.762)
			(stroke
				(width 0.1524)
				(type default)
			)
			(layer "B.SilkS")
		)
		(fp_line
			(start 1.1049 -0.724916)
			(end 1.1049 0.724916)
			(stroke
				(width 0.1)
				(type default)
			)
			(layer "B.Fab")
		)
		(fp_line
			(start -1.1049 -0.724916)
			(end 1.1049 -0.724916)
			(stroke
				(width 0.1)
				(type default)
			)
			(layer "B.Fab")
		)
		(fp_line
			(start 1.1049 0.724916)
			(end -1.1049 0.724916)
			(stroke
				(width 0.1)
				(type default)
			)
			(layer "B.Fab")
		)
		(fp_line
			(start -1.1049 0.724916)
			(end -1.1049 -0.724916)
			(stroke
				(width 0.1)
				(type default)
			)
			(layer "B.Fab")
		)
		(pad "1" smd rect
			(at 0.889 0 90)
			(size 1.016 1.27)
			(layers "B.Cu" "B.Mask" "B.Paste")
			(net "PVPP_HBM_CPU1")
		)
		(pad "2" smd rect
			(at -0.889 0 90)
			(size 1.016 1.27)
			(layers "B.Cu" "B.Mask" "B.Paste")
			(net "GND")
		)
	)
	(footprint ""
		(layer "B.Cu")
		(at 143.0274 -13.762228 90)
		(property "Reference" "R1815"
			(at 0 0 90)
			(layer "B.SilkS")
			(hide yes)
			(effects
				(font
					(size 1.27 1.27)
				)
				(justify mirror)
			)
		)
		(property "Value" ""
			(at 0 0 90)
			(layer "B.Fab")
			(effects
				(font
					(size 1.27 1.27)
				)
				(justify mirror)
			)
		)
		(duplicate_pad_numbers_are_jumpers no)
		(fp_line
			(start 0.7874 -0.4064)
			(end -0.7874 -0.4064)
			(stroke
				(width 0.1524)
				(type default)
			)
			(layer "B.SilkS")
		)
		(fp_line
			(start -0.7874 -0.4064)
			(end -0.7874 0.4064)
			(stroke
				(width 0.1524)
				(type default)
			)
			(layer "B.SilkS")
		)
		(fp_line
			(start 0.7874 0.4064)
			(end 0.7874 -0.4064)
			(stroke
				(width 0.1524)
				(type default)
			)
			(layer "B.SilkS")
		)
		(fp_line
			(start -0.7874 0.4064)
			(end 0.7874 0.4064)
			(stroke
				(width 0.1524)
				(type default)
			)
			(layer "B.SilkS")
		)
		(fp_line
			(start 0.67945 -0.305054)
			(end 0.12065 -0.305054)
			(stroke
				(width 0.1)
				(type default)
			)
			(layer "B.Fab")
		)
		(fp_line
			(start 0.12065 -0.305054)
			(end 0.12065 -0.2794)
			(stroke
				(width 0.1)
				(type default)
			)
			(layer "B.Fab")
		)
		(fp_line
			(start -0.12065 -0.3048)
			(end -0.67945 -0.3048)
			(stroke
				(width 0.1)
				(type default)
			)
			(layer "B.Fab")
		)
		(fp_line
			(start -0.67945 -0.3048)
			(end -0.67945 0.3048)
			(stroke
				(width 0.1)
				(type default)
			)
			(layer "B.Fab")
		)
		(fp_line
			(start 0.12065 -0.2794)
			(end -0.12065 -0.2794)
			(stroke
				(width 0.1)
				(type default)
			)
			(layer "B.Fab")
		)
		(fp_line
			(start -0.12065 -0.2794)
			(end -0.12065 -0.3048)
			(stroke
				(width 0.1)
				(type default)
			)
			(layer "B.Fab")
		)
		(fp_line
			(start 0.12065 0.2794)
			(end 0.12065 0.3048)
			(stroke
				(width 0.1)
				(type default)
			)
			(layer "B.Fab")
		)
		(fp_line
			(start -0.120396 0.2794)
			(end 0.12065 0.2794)
			(stroke
				(width 0.1)
				(type default)
			)
			(layer "B.Fab")
		)
		(fp_line
			(start 0.67945 0.3048)
			(end 0.67945 -0.305054)
			(stroke
				(width 0.1)
				(type default)
			)
			(layer "B.Fab")
		)
		(fp_line
			(start 0.12065 0.3048)
			(end 0.67945 0.3048)
			(stroke
				(width 0.1)
				(type default)
			)
			(layer "B.Fab")
		)
		(fp_line
			(start -0.120396 0.3048)
			(end -0.120396 0.2794)
			(stroke
				(width 0.1)
				(type default)
			)
			(layer "B.Fab")
		)
		(fp_line
			(start -0.67945 0.3048)
			(end -0.120396 0.3048)
			(stroke
				(width 0.1)
				(type default)
			)
			(layer "B.Fab")
		)
		(pad "1" smd circle
			(at 0.40005 0 270)
			(size 0 0)
			(layers "B.Cu" "B.Mask" "B.Paste")
			(net "FM_BMC_PWRBTN_OUT_N")
		)
		(pad "2" smd circle
			(at -0.40005 0 270)
			(size 0 0)
			(layers "B.Cu" "B.Mask" "B.Paste")
			(net "FM_BMC_PWRBTN_OUT_R_N")
		)
	)
	(footprint ""
		(layer "B.Cu")
		(at 430.600104 -132.462778)
		(property "Reference" "R2383"
			(at 0 0 0)
			(layer "B.SilkS")
			(hide yes)
			(effects
				(font
					(size 1.27 1.27)
				)
				(justify mirror)
			)
		)
		(property "Value" ""
			(at 0 0 0)
			(layer "B.Fab")
			(effects
				(font
					(size 1.27 1.27)
				)
				(justify mirror)
			)
		)
		(duplicate_pad_numbers_are_jumpers no)
		(fp_line
			(start -0.7874 -0.4064)
			(end -0.7874 0.4064)
			(stroke
				(width 0.1524)
				(type default)
			)
			(layer "B.SilkS")
		)
		(fp_line
			(start -0.7874 0.4064)
			(end 0.7874 0.4064)
			(stroke
				(width 0.1524)
				(type default)
			)
			(layer "B.SilkS")
		)
		(fp_line
			(start 0.7874 -0.4064)
			(end -0.7874 -0.4064)
			(stroke
				(width 0.1524)
				(type default)
			)
			(layer "B.SilkS")
		)
		(fp_line
			(start 0.7874 0.4064)
			(end 0.7874 -0.4064)
			(stroke
				(width 0.1524)
				(type default)
			)
			(layer "B.SilkS")
		)
		(fp_line
			(start -0.67945 -0.3048)
			(end -0.67945 0.3048)
			(stroke
				(width 0.1)
				(type default)
			)
			(layer "B.Fab")
		)
		(fp_line
			(start -0.67945 0.3048)
			(end -0.120396 0.3048)
			(stroke
				(width 0.1)
				(type default)
			)
			(layer "B.Fab")
		)
		(fp_line
			(start -0.12065 -0.3048)
			(end -0.67945 -0.3048)
			(stroke
				(width 0.1)
				(type default)
			)
			(layer "B.Fab")
		)
		(fp_line
			(start -0.12065 -0.2794)
			(end -0.12065 -0.3048)
			(stroke
				(width 0.1)
				(type default)
			)
			(layer "B.Fab")
		)
		(fp_line
			(start -0.120396 0.2794)
			(end 0.12065 0.2794)
			(stroke
				(width 0.1)
				(type default)
			)
			(layer "B.Fab")
		)
		(fp_line
			(start -0.120396 0.3048)
			(end -0.120396 0.2794)
			(stroke
				(width 0.1)
				(type default)
			)
			(layer "B.Fab")
		)
		(fp_line
			(start 0.12065 -0.305054)
			(end 0.12065 -0.2794)
			(stroke
				(width 0.1)
				(type default)
			)
			(layer "B.Fab")
		)
		(fp_line
			(start 0.12065 -0.2794)
			(end -0.12065 -0.2794)
			(stroke
				(width 0.1)
				(type default)
			)
			(layer "B.Fab")
		)
		(fp_line
			(start 0.12065 0.2794)
			(end 0.12065 0.3048)
			(stroke
				(width 0.1)
				(type default)
			)
			(layer "B.Fab")
		)
		(fp_line
			(start 0.12065 0.3048)
			(end 0.67945 0.3048)
			(stroke
				(width 0.1)
				(type default)
			)
			(layer "B.Fab")
		)
		(fp_line
			(start 0.67945 -0.305054)
			(end 0.12065 -0.305054)
			(stroke
				(width 0.1)
				(type default)
			)
			(layer "B.Fab")
		)
		(fp_line
			(start 0.67945 0.3048)
			(end 0.67945 -0.305054)
			(stroke
				(width 0.1)
				(type default)
			)
			(layer "B.Fab")
		)
		(pad "1" smd circle
			(at 0.40005 0 180)
			(size 0 0)
			(layers "B.Cu" "B.Mask" "B.Paste")
			(net "P3V3_AUX")
		)
		(pad "2" smd circle
			(at -0.40005 0 180)
			(size 0 0)
			(layers "B.Cu" "B.Mask" "B.Paste")
			(net "PWRGD_PVCCINFAON_CPU0_R")
		)
	)
	(footprint ""
		(layer "B.Cu")
		(at 256.271268 -75.32878 90)
		(property "Reference" "R4780"
			(at 0 0 90)
			(layer "B.SilkS")
			(hide yes)
			(effects
				(font
					(size 1.27 1.27)
				)
				(justify mirror)
			)
		)
		(property "Value" ""
			(at 0 0 90)
			(layer "B.Fab")
			(effects
				(font
					(size 1.27 1.27)
				)
				(justify mirror)
			)
		)
		(duplicate_pad_numbers_are_jumpers no)
		(fp_line
			(start 0.7874 -0.4064)
			(end -0.7874 -0.4064)
			(stroke
				(width 0.1524)
				(type default)
			)
			(layer "B.SilkS")
		)
		(fp_line
			(start -0.7874 -0.4064)
			(end -0.7874 0.4064)
			(stroke
				(width 0.1524)
				(type default)
			)
			(layer "B.SilkS")
		)
		(fp_line
			(start 0.7874 0.4064)
			(end 0.7874 -0.4064)
			(stroke
				(width 0.1524)
				(type default)
			)
			(layer "B.SilkS")
		)
		(fp_line
			(start -0.7874 0.4064)
			(end 0.7874 0.4064)
			(stroke
				(width 0.1524)
				(type default)
			)
			(layer "B.SilkS")
		)
		(fp_line
			(start 0.67945 -0.305054)
			(end 0.12065 -0.305054)
			(stroke
				(width 0.1)
				(type default)
			)
			(layer "B.Fab")
		)
		(fp_line
			(start 0.12065 -0.305054)
			(end 0.12065 -0.2794)
			(stroke
				(width 0.1)
				(type default)
			)
			(layer "B.Fab")
		)
		(fp_line
			(start -0.12065 -0.3048)
			(end -0.67945 -0.3048)
			(stroke
				(width 0.1)
				(type default)
			)
			(layer "B.Fab")
		)
		(fp_line
			(start -0.67945 -0.3048)
			(end -0.67945 0.3048)
			(stroke
				(width 0.1)
				(type default)
			)
			(layer "B.Fab")
		)
		(fp_line
			(start 0.12065 -0.2794)
			(end -0.12065 -0.2794)
			(stroke
				(width 0.1)
				(type default)
			)
			(layer "B.Fab")
		)
		(fp_line
			(start -0.12065 -0.2794)
			(end -0.12065 -0.3048)
			(stroke
				(width 0.1)
				(type default)
			)
			(layer "B.Fab")
		)
		(fp_line
			(start 0.12065 0.2794)
			(end 0.12065 0.3048)
			(stroke
				(width 0.1)
				(type default)
			)
			(layer "B.Fab")
		)
		(fp_line
			(start -0.120396 0.2794)
			(end 0.12065 0.2794)
			(stroke
				(width 0.1)
				(type default)
			)
			(layer "B.Fab")
		)
		(fp_line
			(start 0.67945 0.3048)
			(end 0.67945 -0.305054)
			(stroke
				(width 0.1)
				(type default)
			)
			(layer "B.Fab")
		)
		(fp_line
			(start 0.12065 0.3048)
			(end 0.67945 0.3048)
			(stroke
				(width 0.1)
				(type default)
			)
			(layer "B.Fab")
		)
		(fp_line
			(start -0.120396 0.3048)
			(end -0.120396 0.2794)
			(stroke
				(width 0.1)
				(type default)
			)
			(layer "B.Fab")
		)
		(fp_line
			(start -0.67945 0.3048)
			(end -0.120396 0.3048)
			(stroke
				(width 0.1)
				(type default)
			)
			(layer "B.Fab")
		)
		(pad "1" smd circle
			(at 0.40005 0 270)
			(size 0 0)
			(layers "B.Cu" "B.Mask" "B.Paste")
			(net "PWRGD_P1V05_PCH_AUX_R")
		)
		(pad "2" smd circle
			(at -0.40005 0 270)
			(size 0 0)
			(layers "B.Cu" "B.Mask" "B.Paste")
			(net "PWRGD_PVNN_PCH_AUX")
		)
	)
)
